(kicad_pcb
	(version 20260206)
	(generator "pcbnew")
	(generator_version "10.0")
	(general
		(thickness 1.6)
		(legacy_teardrops no)
	)
	(paper "A4")
	(title_block
		(title "04192023_DAF0TMB3IC0_F0TG_MB_C_brd_V02_OCP.brd")
		(comment 1 "Grand Teton / footprints 6405-6412 of 8354")
	)
	(layers
		(0 "F.Cu" signal "TOP")
		(4 "In1.Cu" signal "GND")
		(6 "In2.Cu" signal "IN1")
		(8 "In3.Cu" signal "GND1")
		(10 "In4.Cu" signal "IN2")
		(12 "In5.Cu" signal "GND2")
		(14 "In6.Cu" signal "IN3")
		(16 "In7.Cu" signal "GND3")
		(18 "In8.Cu" signal "VCC")
		(20 "In9.Cu" signal "VCC1")
		(22 "In10.Cu" signal "GND4")
		(24 "In11.Cu" signal "IN4")
		(26 "In12.Cu" signal "GND5")
		(28 "In13.Cu" signal "IN5")
		(30 "In14.Cu" signal "GND6")
		(32 "In15.Cu" signal "IN6")
		(34 "In16.Cu" signal "GND7")
		(2 "B.Cu" signal "BOTTOM")
		(9 "F.Adhes" user "F.Adhesive")
		(11 "B.Adhes" user "B.Adhesive")
		(13 "F.Paste" user "Package Geometry/Pastemask Top")
		(15 "B.Paste" user "Package Geometry/Pastemask Bottom")
		(5 "F.SilkS" user "Ref Des/Silkscreen Top")
		(7 "B.SilkS" user "Ref Des/Silkscreen Bottom")
		(1 "F.Mask" user "Board Geometry/Soldermask Top")
		(3 "B.Mask" user "Board Geometry/Soldermask Bottom")
		(17 "Dwgs.User" user "User.Drawings")
		(19 "Cmts.User" user "User.Comments")
		(21 "Eco1.User" user "User.Eco1")
		(23 "Eco2.User" user "User.Eco2")
		(25 "Edge.Cuts" user "Board Geometry/Outline")
		(27 "Margin" user)
		(31 "F.CrtYd" user "Package Geometry/Place Bound Top")
		(29 "B.CrtYd" user "Package Geometry/Place Bound Bottom")
		(35 "F.Fab" user "Ref Des/Assembly Top")
		(33 "B.Fab" user "Ref Des/Assembly Bottom")
	)
	(footprint ""
		(layer "B.Cu")
		(at 191.992758 -69.443346)
		(property "Reference" "R3213"
			(at 0 0 0)
			(layer "B.SilkS")
			(hide yes)
			(effects
				(font
					(size 1.27 1.27)
				)
				(justify mirror)
			)
		)
		(property "Value" ""
			(at 0 0 0)
			(layer "B.Fab")
			(effects
				(font
					(size 1.27 1.27)
				)
				(justify mirror)
			)
		)
		(duplicate_pad_numbers_are_jumpers no)
		(fp_line
			(start -0.7874 -0.4064)
			(end -0.7874 0.4064)
			(stroke
				(width 0.1524)
				(type default)
			)
			(layer "B.SilkS")
		)
		(fp_line
			(start -0.7874 0.4064)
			(end 0.7874 0.4064)
			(stroke
				(width 0.1524)
				(type default)
			)
			(layer "B.SilkS")
		)
		(fp_line
			(start 0.7874 -0.4064)
			(end -0.7874 -0.4064)
			(stroke
				(width 0.1524)
				(type default)
			)
			(layer "B.SilkS")
		)
		(fp_line
			(start 0.7874 0.4064)
			(end 0.7874 -0.4064)
			(stroke
				(width 0.1524)
				(type default)
			)
			(layer "B.SilkS")
		)
		(fp_line
			(start -0.67945 -0.3048)
			(end -0.67945 0.3048)
			(stroke
				(width 0.1)
				(type default)
			)
			(layer "B.Fab")
		)
		(fp_line
			(start -0.67945 0.3048)
			(end -0.120396 0.3048)
			(stroke
				(width 0.1)
				(type default)
			)
			(layer "B.Fab")
		)
		(fp_line
			(start -0.12065 -0.3048)
			(end -0.67945 -0.3048)
			(stroke
				(width 0.1)
				(type default)
			)
			(layer "B.Fab")
		)
		(fp_line
			(start -0.12065 -0.2794)
			(end -0.12065 -0.3048)
			(stroke
				(width 0.1)
				(type default)
			)
			(layer "B.Fab")
		)
		(fp_line
			(start -0.120396 0.2794)
			(end 0.12065 0.2794)
			(stroke
				(width 0.1)
				(type default)
			)
			(layer "B.Fab")
		)
		(fp_line
			(start -0.120396 0.3048)
			(end -0.120396 0.2794)
			(stroke
				(width 0.1)
				(type default)
			)
			(layer "B.Fab")
		)
		(fp_line
			(start 0.12065 -0.305054)
			(end 0.12065 -0.2794)
			(stroke
				(width 0.1)
				(type default)
			)
			(layer "B.Fab")
		)
		(fp_line
			(start 0.12065 -0.2794)
			(end -0.12065 -0.2794)
			(stroke
				(width 0.1)
				(type default)
			)
			(layer "B.Fab")
		)
		(fp_line
			(start 0.12065 0.2794)
			(end 0.12065 0.3048)
			(stroke
				(width 0.1)
				(type default)
			)
			(layer "B.Fab")
		)
		(fp_line
			(start 0.12065 0.3048)
			(end 0.67945 0.3048)
			(stroke
				(width 0.1)
				(type default)
			)
			(layer "B.Fab")
		)
		(fp_line
			(start 0.67945 -0.305054)
			(end 0.12065 -0.305054)
			(stroke
				(width 0.1)
				(type default)
			)
			(layer "B.Fab")
		)
		(fp_line
			(start 0.67945 0.3048)
			(end 0.67945 -0.305054)
			(stroke
				(width 0.1)
				(type default)
			)
			(layer "B.Fab")
		)
		(pad "1" smd circle
			(at 0.40005 0 180)
			(size 0 0)
			(layers "B.Cu" "B.Mask" "B.Paste")
			(net "NCSI_BMC_TX_EN_R1")
		)
		(pad "2" smd circle
			(at -0.40005 0 180)
			(size 0 0)
			(layers "B.Cu" "B.Mask" "B.Paste")
			(net "RMII_BMC_OCP_TX_EN")
		)
	)
	(footprint ""
		(layer "B.Cu")
		(at 51.884072 -192.66027)
		(property "Reference" "C177"
			(at 0 0 0)
			(layer "B.SilkS")
			(hide yes)
			(effects
				(font
					(size 1.27 1.27)
				)
				(justify mirror)
			)
		)
		(property "Value" ""
			(at 0 0 0)
			(layer "B.Fab")
			(effects
				(font
					(size 1.27 1.27)
				)
				(justify mirror)
			)
		)
		(duplicate_pad_numbers_are_jumpers no)
		(fp_line
			(start -1.524 -0.762)
			(end -1.524 0.762)
			(stroke
				(width 0.1524)
				(type default)
			)
			(layer "B.SilkS")
		)
		(fp_line
			(start -1.524 0.762)
			(end 1.524 0.762)
			(stroke
				(width 0.1524)
				(type default)
			)
			(layer "B.SilkS")
		)
		(fp_line
			(start 1.524 -0.762)
			(end -1.524 -0.762)
			(stroke
				(width 0.1524)
				(type default)
			)
			(layer "B.SilkS")
		)
		(fp_line
			(start 1.524 0.762)
			(end 1.524 -0.762)
			(stroke
				(width 0.1524)
				(type default)
			)
			(layer "B.SilkS")
		)
		(fp_line
			(start -1.1049 -0.724916)
			(end 1.1049 -0.724916)
			(stroke
				(width 0.1)
				(type default)
			)
			(layer "B.Fab")
		)
		(fp_line
			(start -1.1049 0.724916)
			(end -1.1049 -0.724916)
			(stroke
				(width 0.1)
				(type default)
			)
			(layer "B.Fab")
		)
		(fp_line
			(start 1.1049 -0.724916)
			(end 1.1049 0.724916)
			(stroke
				(width 0.1)
				(type default)
			)
			(layer "B.Fab")
		)
		(fp_line
			(start 1.1049 0.724916)
			(end -1.1049 0.724916)
			(stroke
				(width 0.1)
				(type default)
			)
			(layer "B.Fab")
		)
		(pad "1" smd rect
			(at 0.889 0)
			(size 1.016 1.27)
			(layers "B.Cu" "B.Mask" "B.Paste")
			(net "P12V_MEM_CPU1")
		)
		(pad "2" smd rect
			(at -0.889 0)
			(size 1.016 1.27)
			(layers "B.Cu" "B.Mask" "B.Paste")
			(net "GND")
		)
	)
	(footprint ""
		(layer "B.Cu")
		(at 96.575118 -338.968842 -90)
		(property "Reference" "PC429_5"
			(at 0 0 90)
			(layer "B.SilkS")
			(hide yes)
			(effects
				(font
					(size 1.27 1.27)
				)
				(justify mirror)
			)
		)
		(property "Value" ""
			(at 0 0 90)
			(layer "B.Fab")
			(effects
				(font
					(size 1.27 1.27)
				)
				(justify mirror)
			)
		)
		(duplicate_pad_numbers_are_jumpers no)
		(fp_line
			(start -1.524 0.762)
			(end 1.524 0.762)
			(stroke
				(width 0.1524)
				(type default)
			)
			(layer "B.SilkS")
		)
		(fp_line
			(start 1.524 0.762)
			(end 1.524 -0.762)
			(stroke
				(width 0.1524)
				(type default)
			)
			(layer "B.SilkS")
		)
		(fp_line
			(start -1.524 -0.762)
			(end -1.524 0.762)
			(stroke
				(width 0.1524)
				(type default)
			)
			(layer "B.SilkS")
		)
		(fp_line
			(start 1.524 -0.762)
			(end -1.524 -0.762)
			(stroke
				(width 0.1524)
				(type default)
			)
			(layer "B.SilkS")
		)
		(fp_line
			(start -1.1049 0.724916)
			(end -1.1049 -0.724916)
			(stroke
				(width 0.1)
				(type default)
			)
			(layer "B.Fab")
		)
		(fp_line
			(start 1.1049 0.724916)
			(end -1.1049 0.724916)
			(stroke
				(width 0.1)
				(type default)
			)
			(layer "B.Fab")
		)
		(fp_line
			(start -1.1049 -0.724916)
			(end 1.1049 -0.724916)
			(stroke
				(width 0.1)
				(type default)
			)
			(layer "B.Fab")
		)
		(fp_line
			(start 1.1049 -0.724916)
			(end 1.1049 0.724916)
			(stroke
				(width 0.1)
				(type default)
			)
			(layer "B.Fab")
		)
		(pad "1" smd rect
			(at 0.889 0 270)
			(size 1.016 1.27)
			(layers "B.Cu" "B.Mask" "B.Paste")
			(net "SW_P12V_AUX_PVDDCR_CPU1_P1_FLT")
		)
		(pad "2" smd rect
			(at -0.889 0 270)
			(size 1.016 1.27)
			(layers "B.Cu" "B.Mask" "B.Paste")
			(net "GND")
		)
	)
	(footprint ""
		(layer "B.Cu")
		(at 358.389174 -398.455134 180)
		(property "Reference" "C628"
			(at 0 0 0)
			(layer "B.SilkS")
			(hide yes)
			(effects
				(font
					(size 1.27 1.27)
				)
				(justify mirror)
			)
		)
		(property "Value" ""
			(at 0 0 0)
			(layer "B.Fab")
			(effects
				(font
					(size 1.27 1.27)
				)
				(justify mirror)
			)
		)
		(duplicate_pad_numbers_are_jumpers no)
		(fp_line
			(start 1.524 0.762)
			(end 1.524 -0.762)
			(stroke
				(width 0.1524)
				(type default)
			)
			(layer "B.SilkS")
		)
		(fp_line
			(start 1.524 -0.762)
			(end -1.524 -0.762)
			(stroke
				(width 0.1524)
				(type default)
			)
			(layer "B.SilkS")
		)
		(fp_line
			(start -1.524 0.762)
			(end 1.524 0.762)
			(stroke
				(width 0.1524)
				(type default)
			)
			(layer "B.SilkS")
		)
		(fp_line
			(start -1.524 -0.762)
			(end -1.524 0.762)
			(stroke
				(width 0.1524)
				(type default)
			)
			(layer "B.SilkS")
		)
		(fp_line
			(start 1.1049 0.724916)
			(end -1.1049 0.724916)
			(stroke
				(width 0.1)
				(type default)
			)
			(layer "B.Fab")
		)
		(fp_line
			(start 1.1049 -0.724916)
			(end 1.1049 0.724916)
			(stroke
				(width 0.1)
				(type default)
			)
			(layer "B.Fab")
		)
		(fp_line
			(start -1.1049 0.724916)
			(end -1.1049 -0.724916)
			(stroke
				(width 0.1)
				(type default)
			)
			(layer "B.Fab")
		)
		(fp_line
			(start -1.1049 -0.724916)
			(end 1.1049 -0.724916)
			(stroke
				(width 0.1)
				(type default)
			)
			(layer "B.Fab")
		)
		(pad "1" smd rect
			(at 0.889 0 180)
			(size 1.016 1.27)
			(layers "B.Cu" "B.Mask" "B.Paste")
			(net "P0V9_CPU0_RT1_2A")
		)
		(pad "2" smd rect
			(at -0.889 0 180)
			(size 1.016 1.27)
			(layers "B.Cu" "B.Mask" "B.Paste")
			(net "GND")
		)
	)
	(footprint ""
		(layer "B.Cu")
		(at 366.312958 -245.487952 180)
		(property "Reference" "C277"
			(at 0 0 0)
			(layer "B.SilkS")
			(hide yes)
			(effects
				(font
					(size 1.27 1.27)
				)
				(justify mirror)
			)
		)
		(property "Value" ""
			(at 0 0 0)
			(layer "B.Fab")
			(effects
				(font
					(size 1.27 1.27)
				)
				(justify mirror)
			)
		)
		(duplicate_pad_numbers_are_jumpers no)
		(fp_line
			(start 0.7874 0.4064)
			(end 0.7874 -0.4064)
			(stroke
				(width 0.1524)
				(type default)
			)
			(layer "B.SilkS")
		)
		(fp_line
			(start 0.7874 -0.4064)
			(end -0.7874 -0.4064)
			(stroke
				(width 0.1524)
				(type default)
			)
			(layer "B.SilkS")
		)
		(fp_line
			(start -0.7874 0.4064)
			(end 0.7874 0.4064)
			(stroke
				(width 0.1524)
				(type default)
			)
			(layer "B.SilkS")
		)
		(fp_line
			(start -0.7874 -0.4064)
			(end -0.7874 0.4064)
			(stroke
				(width 0.1524)
				(type default)
			)
			(layer "B.SilkS")
		)
		(fp_line
			(start 0.67945 0.3048)
			(end 0.67945 -0.305054)
			(stroke
				(width 0.1)
				(type default)
			)
			(layer "B.Fab")
		)
		(fp_line
			(start 0.67945 -0.305054)
			(end 0.12065 -0.305054)
			(stroke
				(width 0.1)
				(type default)
			)
			(layer "B.Fab")
		)
		(fp_line
			(start 0.12065 0.3048)
			(end 0.67945 0.3048)
			(stroke
				(width 0.1)
				(type default)
			)
			(layer "B.Fab")
		)
		(fp_line
			(start 0.12065 0.2794)
			(end 0.12065 0.3048)
			(stroke
				(width 0.1)
				(type default)
			)
			(layer "B.Fab")
		)
		(fp_line
			(start 0.12065 -0.2794)
			(end -0.12065 -0.2794)
			(stroke
				(width 0.1)
				(type default)
			)
			(layer "B.Fab")
		)
		(fp_line
			(start 0.12065 -0.305054)
			(end 0.12065 -0.2794)
			(stroke
				(width 0.1)
				(type default)
			)
			(layer "B.Fab")
		)
		(fp_line
			(start -0.120396 0.3048)
			(end -0.120396 0.2794)
			(stroke
				(width 0.1)
				(type default)
			)
			(layer "B.Fab")
		)
		(fp_line
			(start -0.120396 0.2794)
			(end 0.12065 0.2794)
			(stroke
				(width 0.1)
				(type default)
			)
			(layer "B.Fab")
		)
		(fp_line
			(start -0.12065 -0.2794)
			(end -0.12065 -0.3048)
			(stroke
				(width 0.1)
				(type default)
			)
			(layer "B.Fab")
		)
		(fp_line
			(start -0.12065 -0.3048)
			(end -0.67945 -0.3048)
			(stroke
				(width 0.1)
				(type default)
			)
			(layer "B.Fab")
		)
		(fp_line
			(start -0.67945 0.3048)
			(end -0.120396 0.3048)
			(stroke
				(width 0.1)
				(type default)
			)
			(layer "B.Fab")
		)
		(fp_line
			(start -0.67945 -0.3048)
			(end -0.67945 0.3048)
			(stroke
				(width 0.1)
				(type default)
			)
			(layer "B.Fab")
		)
		(pad "1" smd circle
			(at 0.40005 0)
			(size 0 0)
			(layers "B.Cu" "B.Mask" "B.Paste")
			(net "PVDDCR_CPU0_P0")
		)
		(pad "2" smd circle
			(at -0.40005 0)
			(size 0 0)
			(layers "B.Cu" "B.Mask" "B.Paste")
			(net "GND")
		)
	)
	(footprint ""
		(layer "B.Cu")
		(at 132.61848 -388.011162 -90)
		(property "Reference" "C495"
			(at 0 0 90)
			(layer "B.SilkS")
			(hide yes)
			(effects
				(font
					(size 1.27 1.27)
				)
				(justify mirror)
			)
		)
		(property "Value" ""
			(at 0 0 90)
			(layer "B.Fab")
			(effects
				(font
					(size 1.27 1.27)
				)
				(justify mirror)
			)
		)
		(duplicate_pad_numbers_are_jumpers no)
		(fp_line
			(start -0.299974 0.150114)
			(end 0.299974 0.150114)
			(stroke
				(width 0.1)
				(type default)
			)
			(layer "B.Fab")
		)
		(fp_line
			(start 0.299974 0.150114)
			(end 0.299974 -0.150114)
			(stroke
				(width 0.1)
				(type default)
			)
			(layer "B.Fab")
		)
		(fp_line
			(start -0.299974 -0.150114)
			(end -0.299974 0.150114)
			(stroke
				(width 0.1)
				(type default)
			)
			(layer "B.Fab")
		)
		(fp_line
			(start 0.299974 -0.150114)
			(end -0.299974 -0.150114)
			(stroke
				(width 0.1)
				(type default)
			)
			(layer "B.Fab")
		)
		(pad "1" smd rect
			(at 0.2667 0 90)
			(size 0.3048 0.381)
			(layers "B.Cu" "B.Mask" "B.Paste")
			(net "P0V9_CPU1_RT3_2A")
		)
		(pad "2" smd rect
			(at -0.2667 0 90)
			(size 0.3048 0.381)
			(layers "B.Cu" "B.Mask" "B.Paste")
			(net "GND")
		)
	)
	(footprint ""
		(layer "B.Cu")
		(at 435.549802 -11.088116 180)
		(property "Reference" "C1239"
			(at 0 0 0)
			(layer "B.SilkS")
			(hide yes)
			(effects
				(font
					(size 1.27 1.27)
				)
				(justify mirror)
			)
		)
		(property "Value" ""
			(at 0 0 0)
			(layer "B.Fab")
			(effects
				(font
					(size 1.27 1.27)
				)
				(justify mirror)
			)
		)
		(duplicate_pad_numbers_are_jumpers no)
		(fp_line
			(start 0.7874 0.4064)
			(end 0.7874 -0.4064)
			(stroke
				(width 0.1524)
				(type default)
			)
			(layer "B.SilkS")
		)
		(fp_line
			(start 0.7874 -0.4064)
			(end -0.7874 -0.4064)
			(stroke
				(width 0.1524)
				(type default)
			)
			(layer "B.SilkS")
		)
		(fp_line
			(start -0.7874 0.4064)
			(end 0.7874 0.4064)
			(stroke
				(width 0.1524)
				(type default)
			)
			(layer "B.SilkS")
		)
		(fp_line
			(start -0.7874 -0.4064)
			(end -0.7874 0.4064)
			(stroke
				(width 0.1524)
				(type default)
			)
			(layer "B.SilkS")
		)
		(fp_line
			(start 0.67945 0.3048)
			(end 0.67945 -0.305054)
			(stroke
				(width 0.1)
				(type default)
			)
			(layer "B.Fab")
		)
		(fp_line
			(start 0.67945 -0.305054)
			(end 0.12065 -0.305054)
			(stroke
				(width 0.1)
				(type default)
			)
			(layer "B.Fab")
		)
		(fp_line
			(start 0.12065 0.3048)
			(end 0.67945 0.3048)
			(stroke
				(width 0.1)
				(type default)
			)
			(layer "B.Fab")
		)
		(fp_line
			(start 0.12065 0.2794)
			(end 0.12065 0.3048)
			(stroke
				(width 0.1)
				(type default)
			)
			(layer "B.Fab")
		)
		(fp_line
			(start 0.12065 -0.2794)
			(end -0.12065 -0.2794)
			(stroke
				(width 0.1)
				(type default)
			)
			(layer "B.Fab")
		)
		(fp_line
			(start 0.12065 -0.305054)
			(end 0.12065 -0.2794)
			(stroke
				(width 0.1)
				(type default)
			)
			(layer "B.Fab")
		)
		(fp_line
			(start -0.120396 0.3048)
			(end -0.120396 0.2794)
			(stroke
				(width 0.1)
				(type default)
			)
			(layer "B.Fab")
		)
		(fp_line
			(start -0.120396 0.2794)
			(end 0.12065 0.2794)
			(stroke
				(width 0.1)
				(type default)
			)
			(layer "B.Fab")
		)
		(fp_line
			(start -0.12065 -0.2794)
			(end -0.12065 -0.3048)
			(stroke
				(width 0.1)
				(type default)
			)
			(layer "B.Fab")
		)
		(fp_line
			(start -0.12065 -0.3048)
			(end -0.67945 -0.3048)
			(stroke
				(width 0.1)
				(type default)
			)
			(layer "B.Fab")
		)
		(fp_line
			(start -0.67945 0.3048)
			(end -0.120396 0.3048)
			(stroke
				(width 0.1)
				(type default)
			)
			(layer "B.Fab")
		)
		(fp_line
			(start -0.67945 -0.3048)
			(end -0.67945 0.3048)
			(stroke
				(width 0.1)
				(type default)
			)
			(layer "B.Fab")
		)
		(pad "1" smd circle
			(at 0.40005 0)
			(size 0 0)
			(layers "B.Cu" "B.Mask" "B.Paste")
			(net "P3V3_OCP_SFF")
		)
		(pad "2" smd circle
			(at -0.40005 0)
			(size 0 0)
			(layers "B.Cu" "B.Mask" "B.Paste")
			(net "GND")
		)
	)
	(footprint ""
		(layer "B.Cu")
		(at 189.865 -97.119948 -90)
		(property "Reference" "R185"
			(at 0 0 90)
			(layer "B.SilkS")
			(hide yes)
			(effects
				(font
					(size 1.27 1.27)
				)
				(justify mirror)
			)
		)
		(property "Value" ""
			(at 0 0 90)
			(layer "B.Fab")
			(effects
				(font
					(size 1.27 1.27)
				)
				(justify mirror)
			)
		)
		(duplicate_pad_numbers_are_jumpers no)
		(fp_line
			(start -0.7874 0.4064)
			(end 0.7874 0.4064)
			(stroke
				(width 0.1524)
				(type default)
			)
			(layer "B.SilkS")
		)
		(fp_line
			(start 0.7874 0.4064)
			(end 0.7874 -0.4064)
			(stroke
				(width 0.1524)
				(type default)
			)
			(layer "B.SilkS")
		)
		(fp_line
			(start -0.7874 -0.4064)
			(end -0.7874 0.4064)
			(stroke
				(width 0.1524)
				(type default)
			)
			(layer "B.SilkS")
		)
		(fp_line
			(start 0.7874 -0.4064)
			(end -0.7874 -0.4064)
			(stroke
				(width 0.1524)
				(type default)
			)
			(layer "B.SilkS")
		)
		(fp_line
			(start -0.67945 0.3048)
			(end -0.120396 0.3048)
			(stroke
				(width 0.1)
				(type default)
			)
			(layer "B.Fab")
		)
		(fp_line
			(start -0.120396 0.3048)
			(end -0.120396 0.2794)
			(stroke
				(width 0.1)
				(type default)
			)
			(layer "B.Fab")
		)
		(fp_line
			(start 0.12065 0.3048)
			(end 0.67945 0.3048)
			(stroke
				(width 0.1)
				(type default)
			)
			(layer "B.Fab")
		)
		(fp_line
			(start 0.67945 0.3048)
			(end 0.67945 -0.305054)
			(stroke
				(width 0.1)
				(type default)
			)
			(layer "B.Fab")
		)
		(fp_line
			(start -0.120396 0.2794)
			(end 0.12065 0.2794)
			(stroke
				(width 0.1)
				(type default)
			)
			(layer "B.Fab")
		)
		(fp_line
			(start 0.12065 0.2794)
			(end 0.12065 0.3048)
			(stroke
				(width 0.1)
				(type default)
			)
			(layer "B.Fab")
		)
		(fp_line
			(start -0.12065 -0.2794)
			(end -0.12065 -0.3048)
			(stroke
				(width 0.1)
				(type default)
			)
			(layer "B.Fab")
		)
		(fp_line
			(start 0.12065 -0.2794)
			(end -0.12065 -0.2794)
			(stroke
				(width 0.1)
				(type default)
			)
			(layer "B.Fab")
		)
		(fp_line
			(start -0.67945 -0.3048)
			(end -0.67945 0.3048)
			(stroke
				(width 0.1)
				(type default)
			)
			(layer "B.Fab")
		)
		(fp_line
			(start -0.12065 -0.3048)
			(end -0.67945 -0.3048)
			(stroke
				(width 0.1)
				(type default)
			)
			(layer "B.Fab")
		)
		(fp_line
			(start 0.12065 -0.305054)
			(end 0.12065 -0.2794)
			(stroke
				(width 0.1)
				(type default)
			)
			(layer "B.Fab")
		)
		(fp_line
			(start 0.67945 -0.305054)
			(end 0.12065 -0.305054)
			(stroke
				(width 0.1)
				(type default)
			)
			(layer "B.Fab")
		)
		(pad "1" smd circle
			(at 0.40005 0 90)
			(size 0 0)
			(layers "B.Cu" "B.Mask" "B.Paste")
			(net "CPU0_CORETYPE2")
		)
		(pad "2" smd circle
			(at -0.40005 0 90)
			(size 0 0)
			(layers "B.Cu" "B.Mask" "B.Paste")
			(net "FM_CPU0_CORETYPE2")
		)
	)
)
